(kicad_pcb
	(version 20221018)
	(generator pcbnew)
	(general
    (thickness 1.7403)
  )
	(paper "A4")
	(title_block
    (title "Data Center RDIMM DDR4 Tester")
    (date "2024-09-30")
    (rev "1.2.4")
		(comment 9 "footprints 101-110 of 690")
	)
	(layers
    (0 "F.Cu" signal)
    (1 "In1.Cu" power)
    (2 "In2.Cu" signal)
    (3 "In3.Cu" power)
    (4 "In4.Cu" power)
    (5 "In5.Cu" signal)
    (6 "In6.Cu" power)
    (7 "In7.Cu" signal)
    (8 "In8.Cu" power)
    (9 "In9.Cu" signal)
    (10 "In10.Cu" power)
    (31 "B.Cu" signal)
    (32 "B.Adhes" user "B.Adhesive")
    (33 "F.Adhes" user "F.Adhesive")
    (34 "B.Paste" user)
    (35 "F.Paste" user)
    (36 "B.SilkS" user "B.Silkscreen")
    (37 "F.SilkS" user "F.Silkscreen")
    (38 "B.Mask" user)
    (39 "F.Mask" user)
    (40 "Dwgs.User" user "User.Drawings")
    (41 "Cmts.User" user "User.Comments")
    (42 "Eco1.User" user "User.Eco1")
    (43 "Eco2.User" user "User.Eco2")
    (44 "Edge.Cuts" user)
    (45 "Margin" user)
    (46 "B.CrtYd" user "B.Courtyard")
    (47 "F.CrtYd" user "F.Courtyard")
    (48 "B.Fab" user)
    (49 "F.Fab" user)
  )
	(footprint "data-center-rdimm-ddr4-tester-footprints:C_0402_1005Metric" (layer "F.Cu")
    (at 151.586328 94.374306 -90)
    (descr "Capacitor SMD 0402")
    (tags "capacitor SMD 0402")
    (property "Author" "Antmicro")
    (property "Dielectric" "")
    (property "License" "Apache-2.0")
    (property "MPN" "GRM155R61A475MEAAD")
    (property "Manufacturer" "Murata")
    (property "Sheetfile" "ethernet.kicad_sch")
    (property "Sheetname" "Ethernet")
    (property "Val" "4u7")
    (property "Voltage" "")
    (property "ki_description" " ")
    (attr smd)
    (fp_text reference "C124" (at -0.654306 2.356328 -90) (layer "F.SilkS")
        (effects (font (size 0.7 0.7) (thickness 0.15)) (justify left bottom))
    )
    (fp_text value "C_4u7_0402" (at 0 1.4 -90) (layer "F.Fab") hide
        (effects (font (size 0.7 0.7) (thickness 0.15)) (justify left bottom))
    )
    (fp_text user "${REFERENCE}" (at -0.932 3.168 -90) (layer "F.Fab") hide
        (effects (font (size 0.7 0.7) (thickness 0.15)) (justify left bottom))
    )
    (fp_text user "Author: Antmicro" (at -0.932 4.17 -90) (layer "F.Fab") hide
        (effects (font (size 0.7 0.7) (thickness 0.15)) (justify left bottom))
    )
    (fp_text user "License: Apache-2.0" (at -0.932 5.17 -90) (layer "F.Fab") hide
        (effects (font (size 0.7 0.7) (thickness 0.15)) (justify left bottom))
    )
    (fp_rect (start -0.94 -0.47) (end 0.94 0.47)
      (stroke (width 0.05) (type solid)) (fill none) (layer "F.CrtYd"))
    (fp_rect (start -0.499 -0.249) (end 0.499 0.249)
      (stroke (width 0.15) (type solid)) (fill none) (layer "F.Fab"))
    (pad "1" smd roundrect (at -0.484 0 270) (size 0.59 0.64) (layers "F.Cu" "F.Paste" "F.Mask") (roundrect_rratio 0.25)
      (net 9 "GND") (pintype "passive"))
    (pad "2" smd roundrect (at 0.484 0 270) (size 0.59 0.64) (layers "F.Cu" "F.Paste" "F.Mask") (roundrect_rratio 0.25)
      (net 178 "/Ethernet/AVDDL_PLL") (pintype "passive"))
  )
	(footprint "data-center-rdimm-ddr4-tester-footprints:C_0402_1005Metric" (layer "F.Cu")
    (at 163.486328 96.774306 90)
    (descr "Capacitor SMD 0402")
    (tags "capacitor SMD 0402")
    (property "Author" "Antmicro")
    (property "Dielectric" "")
    (property "License" "Apache-2.0")
    (property "MPN" "C1005X5R1E474M050BB")
    (property "Manufacturer" "TDK")
    (property "Sheetfile" "ethernet.kicad_sch")
    (property "Sheetname" "Ethernet")
    (property "Val" "470n")
    (property "Voltage" "")
    (property "ki_description" " ")
    (attr smd)
    (fp_text reference "C127" (at -0.825694 2.363672 90) (layer "F.SilkS")
        (effects (font (size 0.7 0.7) (thickness 0.15)) (justify left bottom))
    )
    (fp_text value "C_470n_0402" (at 0 1.4 90) (layer "F.Fab") hide
        (effects (font (size 0.7 0.7) (thickness 0.15)) (justify left bottom))
    )
    (fp_text user "${REFERENCE}" (at -0.932 3.168 90) (layer "F.Fab") hide
        (effects (font (size 0.7 0.7) (thickness 0.15)) (justify left bottom))
    )
    (fp_text user "Author: Antmicro" (at -0.932 4.17 90) (layer "F.Fab") hide
        (effects (font (size 0.7 0.7) (thickness 0.15)) (justify left bottom))
    )
    (fp_text user "License: Apache-2.0" (at -0.932 5.17 90) (layer "F.Fab") hide
        (effects (font (size 0.7 0.7) (thickness 0.15)) (justify left bottom))
    )
    (fp_rect (start -0.94 -0.47) (end 0.94 0.47)
      (stroke (width 0.05) (type solid)) (fill none) (layer "F.CrtYd"))
    (fp_rect (start -0.499 -0.249) (end 0.499 0.249)
      (stroke (width 0.15) (type solid)) (fill none) (layer "F.Fab"))
    (pad "1" smd roundrect (at -0.484 0 90) (size 0.59 0.64) (layers "F.Cu" "F.Paste" "F.Mask") (roundrect_rratio 0.25)
      (net 143 "3V3_SYS") (pintype "passive"))
    (pad "2" smd roundrect (at 0.484 0 90) (size 0.59 0.64) (layers "F.Cu" "F.Paste" "F.Mask") (roundrect_rratio 0.25)
      (net 9 "GND") (pintype "passive"))
  )
	(footprint "data-center-rdimm-ddr4-tester-footprints:C_0402_1005Metric" (layer "F.Cu")
    (at 150.486328 94.374306 -90)
    (descr "Capacitor SMD 0402")
    (tags "capacitor SMD 0402")
    (property "Author" "Antmicro")
    (property "Dielectric" "")
    (property "License" "Apache-2.0")
    (property "MPN" "MC0402B104K160CT")
    (property "Manufacturer" "Multicomp")
    (property "Sheetfile" "ethernet.kicad_sch")
    (property "Sheetname" "Ethernet")
    (property "Val" "100n")
    (property "Voltage" "")
    (property "ki_description" " ")
    (attr smd)
    (fp_text reference "C128" (at -0.654306 2.356328 -90) (layer "F.SilkS")
        (effects (font (size 0.7 0.7) (thickness 0.15)) (justify left bottom))
    )
    (fp_text value "C_100n_16V_0402" (at 0 1.4 -90) (layer "F.Fab") hide
        (effects (font (size 0.7 0.7) (thickness 0.15)) (justify left bottom))
    )
    (fp_text user "${REFERENCE}" (at -0.932 3.168 -90) (layer "F.Fab") hide
        (effects (font (size 0.7 0.7) (thickness 0.15)) (justify left bottom))
    )
    (fp_text user "License: Apache-2.0" (at -0.932 5.17 -90) (layer "F.Fab") hide
        (effects (font (size 0.7 0.7) (thickness 0.15)) (justify left bottom))
    )
    (fp_text user "Author: Antmicro" (at -0.932 4.17 -90) (layer "F.Fab") hide
        (effects (font (size 0.7 0.7) (thickness 0.15)) (justify left bottom))
    )
    (fp_rect (start -0.94 -0.47) (end 0.94 0.47)
      (stroke (width 0.05) (type solid)) (fill none) (layer "F.CrtYd"))
    (fp_rect (start -0.499 -0.249) (end 0.499 0.249)
      (stroke (width 0.15) (type solid)) (fill none) (layer "F.Fab"))
    (pad "1" smd roundrect (at -0.484 0 270) (size 0.59 0.64) (layers "F.Cu" "F.Paste" "F.Mask") (roundrect_rratio 0.25)
      (net 9 "GND") (pintype "passive"))
    (pad "2" smd roundrect (at 0.484 0 270) (size 0.59 0.64) (layers "F.Cu" "F.Paste" "F.Mask") (roundrect_rratio 0.25)
      (net 178 "/Ethernet/AVDDL_PLL") (pintype "passive"))
  )
	(footprint "data-center-rdimm-ddr4-tester-footprints:C_0402_1005Metric" (layer "F.Cu")
    (at 163.486328 99.1 -90)
    (descr "Capacitor SMD 0402")
    (tags "capacitor SMD 0402")
    (property "Author" "Antmicro")
    (property "Dielectric" "")
    (property "License" "Apache-2.0")
    (property "MPN" "C1005X5R1E474M050BB")
    (property "Manufacturer" "TDK")
    (property "Sheetfile" "ethernet.kicad_sch")
    (property "Sheetname" "Ethernet")
    (property "Val" "470n")
    (property "Voltage" "")
    (property "ki_description" " ")
    (attr smd)
    (fp_text reference "C130" (at 1.1 -2.363672 -90) (layer "F.SilkS")
        (effects (font (size 0.7 0.7) (thickness 0.15)) (justify left bottom))
    )
    (fp_text value "C_470n_0402" (at 0 1.4 -90) (layer "F.Fab") hide
        (effects (font (size 0.7 0.7) (thickness 0.15)) (justify left bottom))
    )
    (fp_text user "${REFERENCE}" (at -0.932 3.168 -90) (layer "F.Fab") hide
        (effects (font (size 0.7 0.7) (thickness 0.15)) (justify left bottom))
    )
    (fp_text user "Author: Antmicro" (at -0.932 4.17 -90) (layer "F.Fab") hide
        (effects (font (size 0.7 0.7) (thickness 0.15)) (justify left bottom))
    )
    (fp_text user "License: Apache-2.0" (at -0.932 5.17 -90) (layer "F.Fab") hide
        (effects (font (size 0.7 0.7) (thickness 0.15)) (justify left bottom))
    )
    (fp_rect (start -0.94 -0.47) (end 0.94 0.47)
      (stroke (width 0.05) (type solid)) (fill none) (layer "F.CrtYd"))
    (fp_rect (start -0.499 -0.249) (end 0.499 0.249)
      (stroke (width 0.15) (type solid)) (fill none) (layer "F.Fab"))
    (pad "1" smd roundrect (at -0.484 0 270) (size 0.59 0.64) (layers "F.Cu" "F.Paste" "F.Mask") (roundrect_rratio 0.25)
      (net 306 "1V2_SYS") (pintype "passive"))
    (pad "2" smd roundrect (at 0.484 0 270) (size 0.59 0.64) (layers "F.Cu" "F.Paste" "F.Mask") (roundrect_rratio 0.25)
      (net 9 "GND") (pintype "passive"))
  )
	(footprint "data-center-rdimm-ddr4-tester-footprints:C_0402_1005Metric" (layer "F.Cu")
    (at 149.386328 94.374306 -90)
    (descr "Capacitor SMD 0402")
    (tags "capacitor SMD 0402")
    (property "Author" "Antmicro")
    (property "Dielectric" "X7R")
    (property "License" "Apache-2.0")
    (property "MPN" "GRM155R71H103KA88D")
    (property "Manufacturer" "Murata")
    (property "Sheetfile" "ethernet.kicad_sch")
    (property "Sheetname" "Ethernet")
    (property "Val" "10n")
    (property "Voltage" "50V")
    (property "ki_description" " ")
    (attr smd)
    (fp_text reference "C133" (at -0.654306 2.356328 -90) (layer "F.SilkS")
        (effects (font (size 0.7 0.7) (thickness 0.15)) (justify left bottom))
    )
    (fp_text value "C_10n_0402" (at 0 1.4 -90) (layer "F.Fab") hide
        (effects (font (size 0.7 0.7) (thickness 0.15)) (justify left bottom))
    )
    (fp_text user "Author: Antmicro" (at -0.932 4.17 -90) (layer "F.Fab") hide
        (effects (font (size 0.7 0.7) (thickness 0.15)) (justify left bottom))
    )
    (fp_text user "License: Apache-2.0" (at -0.932 5.17 -90) (layer "F.Fab") hide
        (effects (font (size 0.7 0.7) (thickness 0.15)) (justify left bottom))
    )
    (fp_text user "${REFERENCE}" (at -0.932 3.168 -90) (layer "F.Fab") hide
        (effects (font (size 0.7 0.7) (thickness 0.15)) (justify left bottom))
    )
    (fp_rect (start -0.94 -0.47) (end 0.94 0.47)
      (stroke (width 0.05) (type solid)) (fill none) (layer "F.CrtYd"))
    (fp_rect (start -0.499 -0.249) (end 0.499 0.249)
      (stroke (width 0.15) (type solid)) (fill none) (layer "F.Fab"))
    (pad "1" smd roundrect (at -0.484 0 270) (size 0.59 0.64) (layers "F.Cu" "F.Paste" "F.Mask") (roundrect_rratio 0.25)
      (net 9 "GND") (pintype "passive"))
    (pad "2" smd roundrect (at 0.484 0 270) (size 0.59 0.64) (layers "F.Cu" "F.Paste" "F.Mask") (roundrect_rratio 0.25)
      (net 178 "/Ethernet/AVDDL_PLL") (pintype "passive"))
  )
	(footprint "data-center-rdimm-ddr4-tester-footprints:C_0402_1005Metric" (layer "F.Cu")
    (at 164.586328 93.374306 90)
    (descr "Capacitor SMD 0402")
    (tags "capacitor SMD 0402")
    (property "Author" "Antmicro")
    (property "Dielectric" "X7R")
    (property "License" "Apache-2.0")
    (property "MPN" "GRM155R71H103KA88D")
    (property "Manufacturer" "Murata")
    (property "Sheetfile" "ethernet.kicad_sch")
    (property "Sheetname" "Ethernet")
    (property "Val" "10n")
    (property "Voltage" "50V")
    (property "ki_description" " ")
    (attr smd)
    (fp_text reference "C135" (at -1.395694 1.313672 90) (layer "F.SilkS")
        (effects (font (size 0.7 0.7) (thickness 0.15)) (justify left bottom))
    )
    (fp_text value "C_10n_0402" (at 0 1.4 90) (layer "F.Fab") hide
        (effects (font (size 0.7 0.7) (thickness 0.15)) (justify left bottom))
    )
    (fp_text user "License: Apache-2.0" (at -0.932 5.17 90) (layer "F.Fab") hide
        (effects (font (size 0.7 0.7) (thickness 0.15)) (justify left bottom))
    )
    (fp_text user "Author: Antmicro" (at -0.932 4.17 90) (layer "F.Fab") hide
        (effects (font (size 0.7 0.7) (thickness 0.15)) (justify left bottom))
    )
    (fp_text user "${REFERENCE}" (at -0.932 3.168 90) (layer "F.Fab") hide
        (effects (font (size 0.7 0.7) (thickness 0.15)) (justify left bottom))
    )
    (fp_rect (start -0.94 -0.47) (end 0.94 0.47)
      (stroke (width 0.05) (type solid)) (fill none) (layer "F.CrtYd"))
    (fp_rect (start -0.499 -0.249) (end 0.499 0.249)
      (stroke (width 0.15) (type solid)) (fill none) (layer "F.Fab"))
    (pad "1" smd roundrect (at -0.484 0 90) (size 0.59 0.64) (layers "F.Cu" "F.Paste" "F.Mask") (roundrect_rratio 0.25)
      (net 306 "1V2_SYS") (pintype "passive"))
    (pad "2" smd roundrect (at 0.484 0 90) (size 0.59 0.64) (layers "F.Cu" "F.Paste" "F.Mask") (roundrect_rratio 0.25)
      (net 9 "GND") (pintype "passive"))
  )
	(footprint "data-center-rdimm-ddr4-tester-footprints:C_0402_1005Metric" (layer "F.Cu")
    (at 164.586328 96.774306 90)
    (descr "Capacitor SMD 0402")
    (tags "capacitor SMD 0402")
    (property "Author" "Antmicro")
    (property "Dielectric" "X7R")
    (property "License" "Apache-2.0")
    (property "MPN" "GRM155R71H103KA88D")
    (property "Manufacturer" "Murata")
    (property "Sheetfile" "ethernet.kicad_sch")
    (property "Sheetname" "Ethernet")
    (property "Val" "10n")
    (property "Voltage" "50V")
    (property "ki_description" " ")
    (attr smd)
    (fp_text reference "C139" (at -0.825694 2.363672 90) (layer "F.SilkS")
        (effects (font (size 0.7 0.7) (thickness 0.15)) (justify left bottom))
    )
    (fp_text value "C_10n_0402" (at 0 1.4 90) (layer "F.Fab") hide
        (effects (font (size 0.7 0.7) (thickness 0.15)) (justify left bottom))
    )
    (fp_text user "Author: Antmicro" (at -0.932 4.17 90) (layer "F.Fab") hide
        (effects (font (size 0.7 0.7) (thickness 0.15)) (justify left bottom))
    )
    (fp_text user "${REFERENCE}" (at -0.932 3.168 90) (layer "F.Fab") hide
        (effects (font (size 0.7 0.7) (thickness 0.15)) (justify left bottom))
    )
    (fp_text user "License: Apache-2.0" (at -0.932 5.17 90) (layer "F.Fab") hide
        (effects (font (size 0.7 0.7) (thickness 0.15)) (justify left bottom))
    )
    (fp_rect (start -0.94 -0.47) (end 0.94 0.47)
      (stroke (width 0.05) (type solid)) (fill none) (layer "F.CrtYd"))
    (fp_rect (start -0.499 -0.249) (end 0.499 0.249)
      (stroke (width 0.15) (type solid)) (fill none) (layer "F.Fab"))
    (pad "1" smd roundrect (at -0.484 0 90) (size 0.59 0.64) (layers "F.Cu" "F.Paste" "F.Mask") (roundrect_rratio 0.25)
      (net 143 "3V3_SYS") (pintype "passive"))
    (pad "2" smd roundrect (at 0.484 0 90) (size 0.59 0.64) (layers "F.Cu" "F.Paste" "F.Mask") (roundrect_rratio 0.25)
      (net 9 "GND") (pintype "passive"))
  )
	(footprint "data-center-rdimm-ddr4-tester-footprints:C_0402_1005Metric" (layer "F.Cu")
    (at 164.586328 99.1 -90)
    (descr "Capacitor SMD 0402")
    (tags "capacitor SMD 0402")
    (property "Author" "Antmicro")
    (property "Dielectric" "X7R")
    (property "License" "Apache-2.0")
    (property "MPN" "GRM155R71H103KA88D")
    (property "Manufacturer" "Murata")
    (property "Sheetfile" "ethernet.kicad_sch")
    (property "Sheetname" "Ethernet")
    (property "Val" "10n")
    (property "Voltage" "50V")
    (property "ki_description" " ")
    (attr smd)
    (fp_text reference "C142" (at 1.1 -2.363672 -90) (layer "F.SilkS")
        (effects (font (size 0.7 0.7) (thickness 0.15)) (justify left bottom))
    )
    (fp_text value "C_10n_0402" (at 0 1.4 -90) (layer "F.Fab") hide
        (effects (font (size 0.7 0.7) (thickness 0.15)) (justify left bottom))
    )
    (fp_text user "${REFERENCE}" (at -0.932 3.168 -90) (layer "F.Fab") hide
        (effects (font (size 0.7 0.7) (thickness 0.15)) (justify left bottom))
    )
    (fp_text user "License: Apache-2.0" (at -0.932 5.17 -90) (layer "F.Fab") hide
        (effects (font (size 0.7 0.7) (thickness 0.15)) (justify left bottom))
    )
    (fp_text user "Author: Antmicro" (at -0.932 4.17 -90) (layer "F.Fab") hide
        (effects (font (size 0.7 0.7) (thickness 0.15)) (justify left bottom))
    )
    (fp_rect (start -0.94 -0.47) (end 0.94 0.47)
      (stroke (width 0.05) (type solid)) (fill none) (layer "F.CrtYd"))
    (fp_rect (start -0.499 -0.249) (end 0.499 0.249)
      (stroke (width 0.15) (type solid)) (fill none) (layer "F.Fab"))
    (pad "1" smd roundrect (at -0.484 0 270) (size 0.59 0.64) (layers "F.Cu" "F.Paste" "F.Mask") (roundrect_rratio 0.25)
      (net 306 "1V2_SYS") (pintype "passive"))
    (pad "2" smd roundrect (at 0.484 0 270) (size 0.59 0.64) (layers "F.Cu" "F.Paste" "F.Mask") (roundrect_rratio 0.25)
      (net 9 "GND") (pintype "passive"))
  )
	(footprint "data-center-rdimm-ddr4-tester-footprints:C_0402_1005Metric" (layer "F.Cu")
    (at 149.186328 95.874306 180)
    (descr "Capacitor SMD 0402")
    (tags "capacitor SMD 0402")
    (property "Author" "Antmicro")
    (property "Dielectric" "")
    (property "License" "Apache-2.0")
    (property "MPN" "CC0402JRNPO9BN220")
    (property "Manufacturer" "Yaego")
    (property "Sheetfile" "ethernet.kicad_sch")
    (property "Sheetname" "Ethernet")
    (property "Val" "22p")
    (property "Voltage" "")
    (property "ki_description" " ")
    (attr smd)
    (fp_text reference "C147" (at -0.793672 -0.485694 180) (layer "F.SilkS")
        (effects (font (size 0.7 0.7) (thickness 0.15)) (justify left bottom))
    )
    (fp_text value "C_22p_0402" (at 0 1.4 180) (layer "F.Fab") hide
        (effects (font (size 0.7 0.7) (thickness 0.15)) (justify left bottom))
    )
    (fp_text user "${REFERENCE}" (at -0.932 3.168 180) (layer "F.Fab") hide
        (effects (font (size 0.7 0.7) (thickness 0.15)) (justify left bottom))
    )
    (fp_text user "Author: Antmicro" (at -0.932 4.17 180) (layer "F.Fab") hide
        (effects (font (size 0.7 0.7) (thickness 0.15)) (justify left bottom))
    )
    (fp_text user "License: Apache-2.0" (at -0.932 5.17 180) (layer "F.Fab") hide
        (effects (font (size 0.7 0.7) (thickness 0.15)) (justify left bottom))
    )
    (fp_rect (start -0.94 -0.47) (end 0.94 0.47)
      (stroke (width 0.05) (type solid)) (fill none) (layer "F.CrtYd"))
    (fp_rect (start -0.499 -0.249) (end 0.499 0.249)
      (stroke (width 0.15) (type solid)) (fill none) (layer "F.Fab"))
    (pad "1" smd roundrect (at -0.484 0 180) (size 0.59 0.64) (layers "F.Cu" "F.Paste" "F.Mask") (roundrect_rratio 0.25)
      (net 5 "Net-(U6-XO)") (pintype "passive"))
    (pad "2" smd roundrect (at 0.484 0 180) (size 0.59 0.64) (layers "F.Cu" "F.Paste" "F.Mask") (roundrect_rratio 0.25)
      (net 9 "GND") (pintype "passive"))
  )
	(footprint "data-center-rdimm-ddr4-tester-footprints:C_0402_1005Metric" (layer "F.Cu")
    (at 147.986328 100.674306)
    (descr "Capacitor SMD 0402")
    (tags "capacitor SMD 0402")
    (property "Author" "Antmicro")
    (property "Dielectric" "")
    (property "License" "Apache-2.0")
    (property "MPN" "CC0402JRNPO9BN220")
    (property "Manufacturer" "Yaego")
    (property "Sheetfile" "ethernet.kicad_sch")
    (property "Sheetname" "Ethernet")
    (property "Val" "22p")
    (property "Voltage" "")
    (property "ki_description" " ")
    (attr smd)
    (fp_text reference "C148" (at 0.803672 0.535694) (layer "F.SilkS")
        (effects (font (size 0.7 0.7) (thickness 0.15)) (justify left bottom))
    )
    (fp_text value "C_22p_0402" (at 0 1.4) (layer "F.Fab") hide
        (effects (font (size 0.7 0.7) (thickness 0.15)) (justify left bottom))
    )
    (fp_text user "Author: Antmicro" (at -0.932 4.17) (layer "F.Fab") hide
        (effects (font (size 0.7 0.7) (thickness 0.15)) (justify left bottom))
    )
    (fp_text user "License: Apache-2.0" (at -0.932 5.17) (layer "F.Fab") hide
        (effects (font (size 0.7 0.7) (thickness 0.15)) (justify left bottom))
    )
    (fp_text user "${REFERENCE}" (at -0.932 3.168) (layer "F.Fab") hide
        (effects (font (size 0.7 0.7) (thickness 0.15)) (justify left bottom))
    )
    (fp_rect (start -0.94 -0.47) (end 0.94 0.47)
      (stroke (width 0.05) (type solid)) (fill none) (layer "F.CrtYd"))
    (fp_rect (start -0.499 -0.249) (end 0.499 0.249)
      (stroke (width 0.15) (type solid)) (fill none) (layer "F.Fab"))
    (pad "1" smd roundrect (at -0.484 0) (size 0.59 0.64) (layers "F.Cu" "F.Paste" "F.Mask") (roundrect_rratio 0.25)
      (net 6 "Net-(U6-XI)") (pintype "passive"))
    (pad "2" smd roundrect (at 0.484 0) (size 0.59 0.64) (layers "F.Cu" "F.Paste" "F.Mask") (roundrect_rratio 0.25)
      (net 9 "GND") (pintype "passive"))
  )
)
